# BASEBOARD_FAB2 (Tioga Pass) — schematic netlist excerpt (pin names and nets, part order shuffled) for the footprints in the layout excerpt that follows; sources: Cadence DE-HDL packaged netlist, KiCad conversion of Wiwynn_Tioga_Pass_MB.brd

R1W13  RES  0.0 5% CHIP  pkg 0402  page 176 : A = FM_USB_P0_EN_BOOT_BIOS_STRAP_N ; B = FM_USB_P0_EN_R_N
C5G115  CAP  47UF 4V 20% X6S  pkg 0805  page 243 : A = PVDDQ_KLM ; B = GND
R2U23  RES  0.0 5% CHIP  pkg 0402  page 107 : A = P3E_CPU0_PE1_SS_RXN<4> ; B = P3E_CPU0_PE1_SS_R_RXN<4>

(kicad_pcb
	(version 20260206)
	(generator "pcbnew")
	(generator_version "10.0")
	(general
		(thickness 1.6)
		(legacy_teardrops no)
	)
	(paper "A4")
	(title_block
		(title "Wiwynn_Tioga_Pass_MB.brd")
		(comment 1 "Tioga Pass / footprints 4005-4007 of 4770")
	)
	(layers
		(0 "F.Cu" signal "TOP")
		(4 "In1.Cu" signal "L2GND")
		(6 "In2.Cu" signal "L3")
		(8 "In3.Cu" signal "L4GND")
		(10 "In4.Cu" signal "L5")
		(12 "In5.Cu" signal "L6GND")
		(14 "In6.Cu" signal "L7VCC")
		(16 "In7.Cu" signal "L8VCC")
		(18 "In8.Cu" signal "L9GND")
		(20 "In9.Cu" signal "L10")
		(22 "In10.Cu" signal "L11GND")
		(24 "In11.Cu" signal "L12")
		(26 "In12.Cu" signal "L13GND")
		(2 "B.Cu" signal "BOTTOM")
		(9 "F.Adhes" user "F.Adhesive")
		(11 "B.Adhes" user "B.Adhesive")
		(13 "F.Paste" user "Package Geometry/Pastemask Top")
		(15 "B.Paste" user "Package Geometry/Pastemask Bottom")
		(5 "F.SilkS" user "Ref Des/Silkscreen Top")
		(7 "B.SilkS" user "Ref Des/Silkscreen Bottom")
		(1 "F.Mask" user "Board Geometry/Soldermask Top")
		(3 "B.Mask" user "Board Geometry/Soldermask Bottom")
		(17 "Dwgs.User" user "User.Drawings")
		(19 "Cmts.User" user "User.Comments")
		(21 "Eco1.User" user "User.Eco1")
		(23 "Eco2.User" user "User.Eco2")
		(25 "Edge.Cuts" user "Board Geometry/Outline")
		(27 "Margin" user)
		(31 "F.CrtYd" user "Package Geometry/Place Bound Top")
		(29 "B.CrtYd" user "Package Geometry/Place Bound Bottom")
		(35 "F.Fab" user "Ref Des/Assembly Top")
		(33 "B.Fab" user "Ref Des/Assembly Bottom")
	)
	(footprint ""
		(layer "B.Cu")
		(at 345.919806 -60.368434)
		(property "Reference" "R2U23"
			(at 0 0 0)
			(layer "B.SilkS")
			(hide yes)
			(effects
				(font
					(size 1.27 1.27)
				)
				(justify mirror)
			)
		)
		(property "Value" ""
			(at 0 0 0)
			(layer "B.Fab")
			(effects
				(font
					(size 1.27 1.27)
				)
				(justify mirror)
			)
		)
		(duplicate_pad_numbers_are_jumpers no)
		(fp_poly
			(pts
				(xy 0.2794 -0.1016) (xy -0.2794 -0.1016) (xy -0.2794 0.9906) (xy 0.2794 0.9906)
			)
			(stroke
				(width 0)
				(type default)
			)
			(fill no)
			(layer "B.CrtYd")
		)
		(fp_line
			(start -0.2794 -0.1016)
			(end 0.2794 -0.1016)
			(stroke
				(width 0.1)
				(type default)
			)
			(layer "B.Fab")
		)
		(fp_line
			(start -0.2794 0.9906)
			(end -0.2794 -0.1016)
			(stroke
				(width 0.1)
				(type default)
			)
			(layer "B.Fab")
		)
		(fp_line
			(start 0.2794 -0.1016)
			(end 0.2794 0.9906)
			(stroke
				(width 0.1)
				(type default)
			)
			(layer "B.Fab")
		)
		(fp_line
			(start 0.2794 0.9906)
			(end -0.2794 0.9906)
			(stroke
				(width 0.1)
				(type default)
			)
			(layer "B.Fab")
		)
		(pad "1" smd rect
			(at 0 0 180)
			(size 0.508 0.508)
			(layers "B.Cu" "B.Mask" "B.Paste")
			(net "P3E_CPU0_PE1_SS_RXN<4>")
		)
		(pad "2" smd rect
			(at 0 0.889 180)
			(size 0.508 0.508)
			(layers "B.Cu" "B.Mask" "B.Paste")
			(net "P3E_CPU0_PE1_SS_R_RXN<4>")
		)
		(zone
			(layer "B.Cu")
			(hatch none 0.5)
			(connect_pads
				(clearance 0)
			)
			(min_thickness 0.25)
			(keepout
				(tracks allowed)
				(vias not_allowed)
				(pads allowed)
				(copperpour not_allowed)
				(footprints allowed)
			)
			(placement
				(enabled no)
				(sheetname "")
			)
			(fill
				(thermal_gap 0.5)
				(thermal_bridge_width 0.5)
				(island_removal_mode 0)
			)
			(polygon
				(pts
					(xy 346.173806 -60.114434) (xy 345.665806 -60.114434) (xy 345.665806 -59.733434) (xy 346.173806 -59.733434)
				)
			)
		)
	)
	(footprint ""
		(layer "B.Cu")
		(at 468.884 -125.984 180)
		(property "Reference" "R1W13"
			(at 0.8382 -0.67818 180)
			(unlocked yes)
			(layer "B.SilkS")
			(effects
				(font
					(size 0.4064 0.254)
					(thickness 0.1524)
				)
				(justify left mirror)
			)
		)
		(property "Value" ""
			(at 0 0 0)
			(layer "B.Fab")
			(effects
				(font
					(size 1.27 1.27)
				)
				(justify mirror)
			)
		)
		(duplicate_pad_numbers_are_jumpers no)
		(fp_poly
			(pts
				(xy 0.2794 -0.1016) (xy -0.2794 -0.1016) (xy -0.2794 0.9906) (xy 0.2794 0.9906)
			)
			(stroke
				(width 0)
				(type default)
			)
			(fill no)
			(layer "B.CrtYd")
		)
		(fp_line
			(start 0.2794 0.9906)
			(end -0.2794 0.9906)
			(stroke
				(width 0.1)
				(type default)
			)
			(layer "B.Fab")
		)
		(fp_line
			(start 0.2794 -0.1016)
			(end 0.2794 0.9906)
			(stroke
				(width 0.1)
				(type default)
			)
			(layer "B.Fab")
		)
		(fp_line
			(start -0.2794 0.9906)
			(end -0.2794 -0.1016)
			(stroke
				(width 0.1)
				(type default)
			)
			(layer "B.Fab")
		)
		(fp_line
			(start -0.2794 -0.1016)
			(end 0.2794 -0.1016)
			(stroke
				(width 0.1)
				(type default)
			)
			(layer "B.Fab")
		)
		(pad "1" smd rect
			(at 0 0)
			(size 0.508 0.508)
			(layers "B.Cu" "B.Mask" "B.Paste")
			(net "FM_USB_P0_EN_BOOT_BIOS_STRAP_N")
		)
		(pad "2" smd rect
			(at 0 0.889)
			(size 0.508 0.508)
			(layers "B.Cu" "B.Mask" "B.Paste")
			(net "FM_USB_P0_EN_R_N")
		)
		(zone
			(layer "B.Cu")
			(hatch none 0.5)
			(connect_pads
				(clearance 0)
			)
			(min_thickness 0.25)
			(keepout
				(tracks not_allowed)
				(vias allowed)
				(pads allowed)
				(copperpour not_allowed)
				(footprints allowed)
			)
			(placement
				(enabled no)
				(sheetname "")
			)
			(fill
				(thermal_gap 0.5)
				(thermal_bridge_width 0.5)
				(island_removal_mode 0)
			)
			(polygon
				(pts
					(xy 468.63 -126.619) (xy 469.138 -126.619) (xy 469.138 -126.238) (xy 468.63 -126.238)
				)
			)
		)
		(zone
			(layer "B.Cu")
			(hatch none 0.5)
			(connect_pads
				(clearance 0)
			)
			(min_thickness 0.25)
			(keepout
				(tracks allowed)
				(vias not_allowed)
				(pads allowed)
				(copperpour not_allowed)
				(footprints allowed)
			)
			(placement
				(enabled no)
				(sheetname "")
			)
			(fill
				(thermal_gap 0.5)
				(thermal_bridge_width 0.5)
				(island_removal_mode 0)
			)
			(polygon
				(pts
					(xy 468.63 -126.238) (xy 469.138 -126.238) (xy 469.138 -126.619) (xy 468.63 -126.619)
				)
			)
		)
	)
	(footprint ""
		(layer "B.Cu")
		(at 94.26448 -140.04544 90)
		(property "Reference" "C5G115"
			(at -1.64973 0.78994 180)
			(unlocked yes)
			(layer "B.SilkS")
			(effects
				(font
					(size 0.7874 0.5842)
					(thickness 0.1524)
				)
				(justify mirror)
			)
		)
		(property "Value" ""
			(at 0 0 90)
			(layer "B.Fab")
			(effects
				(font
					(size 1.27 1.27)
				)
				(justify mirror)
			)
		)
		(duplicate_pad_numbers_are_jumpers no)
		(fp_rect
			(start -0.7239 -0.2159)
			(end 0.7239 1.9939)
			(stroke
				(width 0)
				(type default)
			)
			(fill no)
			(layer "B.CrtYd")
		)
		(fp_line
			(start 0.7239 -0.2159)
			(end 0.7239 1.9939)
			(stroke
				(width 0.1)
				(type default)
			)
			(layer "B.Fab")
		)
		(fp_line
			(start -0.7239 -0.2159)
			(end 0.7239 -0.2159)
			(stroke
				(width 0.1)
				(type default)
			)
			(layer "B.Fab")
		)
		(fp_line
			(start 0.7239 1.9939)
			(end -0.7239 1.9939)
			(stroke
				(width 0.1)
				(type default)
			)
			(layer "B.Fab")
		)
		(fp_line
			(start -0.7239 1.9939)
			(end -0.7239 -0.2159)
			(stroke
				(width 0.1)
				(type default)
			)
			(layer "B.Fab")
		)
		(pad "1" smd rect
			(at 0 0 270)
			(size 1.27 1.016)
			(layers "B.Cu" "B.Mask" "B.Paste")
			(net "PVDDQ_KLM")
		)
		(pad "2" smd rect
			(at 0 1.778 270)
			(size 1.27 1.016)
			(layers "B.Cu" "B.Mask" "B.Paste")
			(net "GND")
		)
		(zone
			(layer "B.Cu")
			(hatch none 0.5)
			(connect_pads
				(clearance 0)
			)
			(min_thickness 0.25)
			(keepout
				(tracks not_allowed)
				(vias allowed)
				(pads allowed)
				(copperpour not_allowed)
				(footprints allowed)
			)
			(placement
				(enabled no)
				(sheetname "")
			)
			(fill
				(thermal_gap 0.5)
				(thermal_bridge_width 0.5)
				(island_removal_mode 0)
			)
			(polygon
				(pts
					(xy 94.77248 -139.41044) (xy 95.53448 -139.41044) (xy 95.53448 -140.68044) (xy 94.77248 -140.68044)
				)
			)
		)
	)
)
